# T6G (Grand Teton) — schematic netlist excerpt (pin names and nets, part order shuffled) for the footprints in the layout excerpt that follows; sources: Cadence DE-HDL packaged netlist, KiCad conversion of 04192023_DAF0TMB3IC0_F0TG_MB_C_brd_V02_OCP.brd

R8001  Q_RES  100K 1% EMPTY  pkg 0402LF  page 123 : A = PRSNT_SWB_N ; B = GND
R3514  Q_RES  54.9K 1% CHIP  pkg 0402LF  page 127 : A = P3V3_AUX ; B = FM_SMB_2_ALERT_GPU_N

(kicad_pcb
	(version 20260206)
	(generator "pcbnew")
	(generator_version "10.0")
	(general
		(thickness 1.6)
		(legacy_teardrops no)
	)
	(paper "A4")
	(title_block
		(title "04192023_DAF0TMB3IC0_F0TG_MB_C_brd_V02_OCP.brd")
		(comment 1 "Grand Teton / footprints 6316-6317 of 8354")
	)
	(layers
		(0 "F.Cu" signal "TOP")
		(4 "In1.Cu" signal "GND")
		(6 "In2.Cu" signal "IN1")
		(8 "In3.Cu" signal "GND1")
		(10 "In4.Cu" signal "IN2")
		(12 "In5.Cu" signal "GND2")
		(14 "In6.Cu" signal "IN3")
		(16 "In7.Cu" signal "GND3")
		(18 "In8.Cu" signal "VCC")
		(20 "In9.Cu" signal "VCC1")
		(22 "In10.Cu" signal "GND4")
		(24 "In11.Cu" signal "IN4")
		(26 "In12.Cu" signal "GND5")
		(28 "In13.Cu" signal "IN5")
		(30 "In14.Cu" signal "GND6")
		(32 "In15.Cu" signal "IN6")
		(34 "In16.Cu" signal "GND7")
		(2 "B.Cu" signal "BOTTOM")
		(9 "F.Adhes" user "F.Adhesive")
		(11 "B.Adhes" user "B.Adhesive")
		(13 "F.Paste" user "Package Geometry/Pastemask Top")
		(15 "B.Paste" user "Package Geometry/Pastemask Bottom")
		(5 "F.SilkS" user "Ref Des/Silkscreen Top")
		(7 "B.SilkS" user "Ref Des/Silkscreen Bottom")
		(1 "F.Mask" user "Board Geometry/Soldermask Top")
		(3 "B.Mask" user "Board Geometry/Soldermask Bottom")
		(17 "Dwgs.User" user "User.Drawings")
		(19 "Cmts.User" user "User.Comments")
		(21 "Eco1.User" user "User.Eco1")
		(23 "Eco2.User" user "User.Eco2")
		(25 "Edge.Cuts" user "Board Geometry/Outline")
		(27 "Margin" user)
		(31 "F.CrtYd" user "Package Geometry/Place Bound Top")
		(29 "B.CrtYd" user "Package Geometry/Place Bound Bottom")
		(35 "F.Fab" user "Ref Des/Assembly Top")
		(33 "B.Fab" user "Ref Des/Assembly Bottom")
	)
	(footprint ""
		(layer "B.Cu")
		(at 105.537 -421.005 180)
		(property "Reference" "R3514"
			(at 0 0 0)
			(layer "B.SilkS")
			(hide yes)
			(effects
				(font
					(size 1.27 1.27)
				)
				(justify mirror)
			)
		)
		(property "Value" ""
			(at 0 0 0)
			(layer "B.Fab")
			(effects
				(font
					(size 1.27 1.27)
				)
				(justify mirror)
			)
		)
		(duplicate_pad_numbers_are_jumpers no)
		(fp_line
			(start 0.7874 0.4064)
			(end 0.7874 -0.4064)
			(stroke
				(width 0.1524)
				(type default)
			)
			(layer "B.SilkS")
		)
		(fp_line
			(start 0.7874 -0.4064)
			(end -0.7874 -0.4064)
			(stroke
				(width 0.1524)
				(type default)
			)
			(layer "B.SilkS")
		)
		(fp_line
			(start -0.7874 0.4064)
			(end 0.7874 0.4064)
			(stroke
				(width 0.1524)
				(type default)
			)
			(layer "B.SilkS")
		)
		(fp_line
			(start -0.7874 -0.4064)
			(end -0.7874 0.4064)
			(stroke
				(width 0.1524)
				(type default)
			)
			(layer "B.SilkS")
		)
		(fp_line
			(start 0.67945 0.3048)
			(end 0.67945 -0.305054)
			(stroke
				(width 0.1)
				(type default)
			)
			(layer "B.Fab")
		)
		(fp_line
			(start 0.67945 -0.305054)
			(end 0.12065 -0.305054)
			(stroke
				(width 0.1)
				(type default)
			)
			(layer "B.Fab")
		)
		(fp_line
			(start 0.12065 0.3048)
			(end 0.67945 0.3048)
			(stroke
				(width 0.1)
				(type default)
			)
			(layer "B.Fab")
		)
		(fp_line
			(start 0.12065 0.2794)
			(end 0.12065 0.3048)
			(stroke
				(width 0.1)
				(type default)
			)
			(layer "B.Fab")
		)
		(fp_line
			(start 0.12065 -0.2794)
			(end -0.12065 -0.2794)
			(stroke
				(width 0.1)
				(type default)
			)
			(layer "B.Fab")
		)
		(fp_line
			(start 0.12065 -0.305054)
			(end 0.12065 -0.2794)
			(stroke
				(width 0.1)
				(type default)
			)
			(layer "B.Fab")
		)
		(fp_line
			(start -0.120396 0.3048)
			(end -0.120396 0.2794)
			(stroke
				(width 0.1)
				(type default)
			)
			(layer "B.Fab")
		)
		(fp_line
			(start -0.120396 0.2794)
			(end 0.12065 0.2794)
			(stroke
				(width 0.1)
				(type default)
			)
			(layer "B.Fab")
		)
		(fp_line
			(start -0.12065 -0.2794)
			(end -0.12065 -0.3048)
			(stroke
				(width 0.1)
				(type default)
			)
			(layer "B.Fab")
		)
		(fp_line
			(start -0.12065 -0.3048)
			(end -0.67945 -0.3048)
			(stroke
				(width 0.1)
				(type default)
			)
			(layer "B.Fab")
		)
		(fp_line
			(start -0.67945 0.3048)
			(end -0.120396 0.3048)
			(stroke
				(width 0.1)
				(type default)
			)
			(layer "B.Fab")
		)
		(fp_line
			(start -0.67945 -0.3048)
			(end -0.67945 0.3048)
			(stroke
				(width 0.1)
				(type default)
			)
			(layer "B.Fab")
		)
		(pad "1" smd circle
			(at 0.40005 0)
			(size 0 0)
			(layers "B.Cu" "B.Mask" "B.Paste")
			(net "P3V3_AUX")
		)
		(pad "2" smd circle
			(at -0.40005 0)
			(size 0 0)
			(layers "B.Cu" "B.Mask" "B.Paste")
			(net "FM_SMB_2_ALERT_GPU_N")
		)
	)
	(footprint ""
		(layer "B.Cu")
		(at 97.591118 -424.191684)
		(property "Reference" "R8001"
			(at 0 0 0)
			(layer "B.SilkS")
			(hide yes)
			(effects
				(font
					(size 1.27 1.27)
				)
				(justify mirror)
			)
		)
		(property "Value" ""
			(at 0 0 0)
			(layer "B.Fab")
			(effects
				(font
					(size 1.27 1.27)
				)
				(justify mirror)
			)
		)
		(duplicate_pad_numbers_are_jumpers no)
		(fp_line
			(start -0.7874 -0.4064)
			(end -0.7874 0.4064)
			(stroke
				(width 0.1524)
				(type default)
			)
			(layer "B.SilkS")
		)
		(fp_line
			(start -0.7874 0.4064)
			(end 0.7874 0.4064)
			(stroke
				(width 0.1524)
				(type default)
			)
			(layer "B.SilkS")
		)
		(fp_line
			(start 0.7874 -0.4064)
			(end -0.7874 -0.4064)
			(stroke
				(width 0.1524)
				(type default)
			)
			(layer "B.SilkS")
		)
		(fp_line
			(start 0.7874 0.4064)
			(end 0.7874 -0.4064)
			(stroke
				(width 0.1524)
				(type default)
			)
			(layer "B.SilkS")
		)
		(fp_line
			(start -0.67945 -0.3048)
			(end -0.67945 0.3048)
			(stroke
				(width 0.1)
				(type default)
			)
			(layer "B.Fab")
		)
		(fp_line
			(start -0.67945 0.3048)
			(end -0.120396 0.3048)
			(stroke
				(width 0.1)
				(type default)
			)
			(layer "B.Fab")
		)
		(fp_line
			(start -0.12065 -0.3048)
			(end -0.67945 -0.3048)
			(stroke
				(width 0.1)
				(type default)
			)
			(layer "B.Fab")
		)
		(fp_line
			(start -0.12065 -0.2794)
			(end -0.12065 -0.3048)
			(stroke
				(width 0.1)
				(type default)
			)
			(layer "B.Fab")
		)
		(fp_line
			(start -0.120396 0.2794)
			(end 0.12065 0.2794)
			(stroke
				(width 0.1)
				(type default)
			)
			(layer "B.Fab")
		)
		(fp_line
			(start -0.120396 0.3048)
			(end -0.120396 0.2794)
			(stroke
				(width 0.1)
				(type default)
			)
			(layer "B.Fab")
		)
		(fp_line
			(start 0.12065 -0.305054)
			(end 0.12065 -0.2794)
			(stroke
				(width 0.1)
				(type default)
			)
			(layer "B.Fab")
		)
		(fp_line
			(start 0.12065 -0.2794)
			(end -0.12065 -0.2794)
			(stroke
				(width 0.1)
				(type default)
			)
			(layer "B.Fab")
		)
		(fp_line
			(start 0.12065 0.2794)
			(end 0.12065 0.3048)
			(stroke
				(width 0.1)
				(type default)
			)
			(layer "B.Fab")
		)
		(fp_line
			(start 0.12065 0.3048)
			(end 0.67945 0.3048)
			(stroke
				(width 0.1)
				(type default)
			)
			(layer "B.Fab")
		)
		(fp_line
			(start 0.67945 -0.305054)
			(end 0.12065 -0.305054)
			(stroke
				(width 0.1)
				(type default)
			)
			(layer "B.Fab")
		)
		(fp_line
			(start 0.67945 0.3048)
			(end 0.67945 -0.305054)
			(stroke
				(width 0.1)
				(type default)
			)
			(layer "B.Fab")
		)
		(pad "1" smd circle
			(at 0.40005 0 180)
			(size 0 0)
			(layers "B.Cu" "B.Mask" "B.Paste")
			(net "PRSNT_SWB_N")
		)
		(pad "2" smd circle
			(at -0.40005 0 180)
			(size 0 0)
			(layers "B.Cu" "B.Mask" "B.Paste")
			(net "GND")
		)
	)
)
